# BASEBOARD_FAB2 (Tioga Pass) — schematic netlist excerpt (pin names and nets, part order shuffled) for the footprints in the layout excerpt that follows; sources: Cadence DE-HDL packaged netlist, KiCad conversion of Wiwynn_Tioga_Pass_MB.brd

R4D39  RES  10.0 1% CHIP  pkg 0402  page 201 : A = VSENSE_PVSA_CPU0_P ; B = VSENSE_PVSA_CPU0_BVSP

Q9B1  2SB2907A-B0-00001-GP  pkg DISCRET-GB1  page 167
  B  = ISENSE_TMP421_1_BC
  C  = ISENSE_TMP421_1_BC
  E  = ISENSE_TMP421_1_E

(kicad_pcb
	(version 20260206)
	(generator "pcbnew")
	(generator_version "10.0")
	(general
		(thickness 1.6)
		(legacy_teardrops no)
	)
	(paper "A4")
	(title_block
		(title "Wiwynn_Tioga_Pass_MB.brd")
		(comment 1 "Tioga Pass / footprints 2189-2190 of 4770")
	)
	(layers
		(0 "F.Cu" signal "TOP")
		(4 "In1.Cu" signal "L2GND")
		(6 "In2.Cu" signal "L3")
		(8 "In3.Cu" signal "L4GND")
		(10 "In4.Cu" signal "L5")
		(12 "In5.Cu" signal "L6GND")
		(14 "In6.Cu" signal "L7VCC")
		(16 "In7.Cu" signal "L8VCC")
		(18 "In8.Cu" signal "L9GND")
		(20 "In9.Cu" signal "L10")
		(22 "In10.Cu" signal "L11GND")
		(24 "In11.Cu" signal "L12")
		(26 "In12.Cu" signal "L13GND")
		(2 "B.Cu" signal "BOTTOM")
		(9 "F.Adhes" user "F.Adhesive")
		(11 "B.Adhes" user "B.Adhesive")
		(13 "F.Paste" user "Package Geometry/Pastemask Top")
		(15 "B.Paste" user "Package Geometry/Pastemask Bottom")
		(5 "F.SilkS" user "Ref Des/Silkscreen Top")
		(7 "B.SilkS" user "Ref Des/Silkscreen Bottom")
		(1 "F.Mask" user "Board Geometry/Soldermask Top")
		(3 "B.Mask" user "Board Geometry/Soldermask Bottom")
		(17 "Dwgs.User" user "User.Drawings")
		(19 "Cmts.User" user "User.Comments")
		(21 "Eco1.User" user "User.Eco1")
		(23 "Eco2.User" user "User.Eco2")
		(25 "Edge.Cuts" user "Board Geometry/Outline")
		(27 "Margin" user)
		(31 "F.CrtYd" user "Package Geometry/Place Bound Top")
		(29 "B.CrtYd" user "Package Geometry/Place Bound Bottom")
		(35 "F.Fab" user "Ref Des/Assembly Top")
		(33 "B.Fab" user "Ref Des/Assembly Bottom")
	)
	(footprint ""
		(layer "F.Cu")
		(at 189.70498 -73.5457)
		(property "Reference" "R4D39"
			(at 0 0 0)
			(layer "F.SilkS")
			(hide yes)
			(effects
				(font
					(size 1.27 1.27)
				)
			)
		)
		(property "Value" ""
			(at 0 0 0)
			(layer "F.Fab")
			(effects
				(font
					(size 1.27 1.27)
				)
			)
		)
		(duplicate_pad_numbers_are_jumpers no)
		(fp_rect
			(start -0.2794 0.9906)
			(end 0.2794 -0.1016)
			(stroke
				(width 0)
				(type default)
			)
			(fill no)
			(layer "F.CrtYd")
		)
		(fp_line
			(start -0.2794 -0.1016)
			(end -0.2794 0.9906)
			(stroke
				(width 0.1)
				(type default)
			)
			(layer "F.Fab")
		)
		(fp_line
			(start -0.2794 0.9906)
			(end 0.2794 0.9906)
			(stroke
				(width 0.1)
				(type default)
			)
			(layer "F.Fab")
		)
		(fp_line
			(start 0.2794 -0.1016)
			(end -0.2794 -0.1016)
			(stroke
				(width 0.1)
				(type default)
			)
			(layer "F.Fab")
		)
		(fp_line
			(start 0.2794 0.9906)
			(end 0.2794 -0.1016)
			(stroke
				(width 0.1)
				(type default)
			)
			(layer "F.Fab")
		)
		(pad "1" smd rect
			(at 0 0)
			(size 0.508 0.508)
			(layers "F.Cu" "F.Mask" "F.Paste")
			(net "VSENSE_PVSA_CPU0_P")
		)
		(pad "2" smd rect
			(at 0 0.889)
			(size 0.508 0.508)
			(layers "F.Cu" "F.Mask" "F.Paste")
			(net "VSENSE_PVSA_CPU0_BVSP")
		)
		(zone
			(layer "F.Cu")
			(hatch none 0.5)
			(connect_pads
				(clearance 0)
			)
			(min_thickness 0.25)
			(keepout
				(tracks not_allowed)
				(vias allowed)
				(pads allowed)
				(copperpour not_allowed)
				(footprints allowed)
			)
			(placement
				(enabled no)
				(sheetname "")
			)
			(fill
				(thermal_gap 0.5)
				(thermal_bridge_width 0.5)
				(island_removal_mode 0)
			)
			(polygon
				(pts
					(xy 189.45098 -72.9107) (xy 189.95898 -72.9107) (xy 189.95898 -73.2917) (xy 189.45098 -73.2917)
				)
			)
		)
		(zone
			(layer "F.Cu")
			(hatch none 0.5)
			(connect_pads
				(clearance 0)
			)
			(min_thickness 0.25)
			(keepout
				(tracks allowed)
				(vias not_allowed)
				(pads allowed)
				(copperpour not_allowed)
				(footprints allowed)
			)
			(placement
				(enabled no)
				(sheetname "")
			)
			(fill
				(thermal_gap 0.5)
				(thermal_bridge_width 0.5)
				(island_removal_mode 0)
			)
			(polygon
				(pts
					(xy 189.45098 -72.9107) (xy 189.95898 -72.9107) (xy 189.95898 -73.2917) (xy 189.45098 -73.2917)
				)
			)
		)
	)
	(footprint ""
		(layer "F.Cu")
		(at 488.887516 -125.92685 180)
		(property "Reference" "Q9B1"
			(at 0 0 180)
			(layer "F.SilkS")
			(hide yes)
			(effects
				(font
					(size 1.27 1.27)
				)
			)
		)
		(property "Value" "*"
			(at -4.8514 -0.40005 180)
			(unlocked yes)
			(layer "F.Fab")
			(hide yes)
			(effects
				(font
					(size 0.889 0.889)
					(thickness 0.1524)
				)
			)
		)
		(property "Device Type" "2SB2907A-B0-00001-GP_DISCRET-GA"
			(at -4.8514 -1.92405 180)
			(unlocked yes)
			(layer "F.Fab")
			(hide yes)
			(effects
				(font
					(size 0.889 0.889)
					(thickness 0.1524)
				)
			)
		)
		(duplicate_pad_numbers_are_jumpers no)
		(fp_line
			(start 3.3274 0.8255)
			(end 2.59334 0.8255)
			(stroke
				(width 0.1524)
				(type default)
			)
			(layer "F.SilkS")
		)
		(fp_line
			(start 3.3274 -0.8255)
			(end 3.3274 0.8255)
			(stroke
				(width 0.1524)
				(type default)
			)
			(layer "F.SilkS")
		)
		(fp_line
			(start 2.460752 -0.8255)
			(end 3.3274 -0.8255)
			(stroke
				(width 0.1524)
				(type default)
			)
			(layer "F.SilkS")
		)
		(fp_line
			(start -2.188718 -1.3208)
			(end 2.188718 -1.3208)
			(stroke
				(width 0.1524)
				(type default)
			)
			(layer "F.SilkS")
		)
		(fp_line
			(start -2.59334 0.8255)
			(end -3.3274 0.8255)
			(stroke
				(width 0.1524)
				(type default)
			)
			(layer "F.SilkS")
		)
		(fp_line
			(start -3.3274 0.8255)
			(end -3.3274 -0.8255)
			(stroke
				(width 0.1524)
				(type default)
			)
			(layer "F.SilkS")
		)
		(fp_line
			(start -3.3274 -0.8255)
			(end -2.460752 -0.8255)
			(stroke
				(width 0.1524)
				(type default)
			)
			(layer "F.SilkS")
		)
		(fp_arc
			(start 2.59334 0.8255)
			(mid 0 2.870159)
			(end -2.59334 0.8255)
			(stroke
				(width 0.1524)
				(type default)
			)
			(layer "F.SilkS")
		)
		(fp_arc
			(start 2.188718 -1.3208)
			(mid 2.337892 -1.080376)
			(end 2.460752 -0.8255)
			(stroke
				(width 0.1524)
				(type default)
			)
			(layer "F.SilkS")
		)
		(fp_arc
			(start -2.460752 -0.8255)
			(mid -2.337885 -1.080372)
			(end -2.188718 -1.3208)
			(stroke
				(width 0.1524)
				(type default)
			)
			(layer "F.SilkS")
		)
		(fp_poly
			(pts
				(arc
					(start 2.413 0.2286)
					(mid 0 2.616334)
					(end -2.413 0.2286)
				)
				(xy -2.7432 0.2286) (xy -2.7432 -0.2286)
				(arc
					(start -2.374138 -0.2286)
					(mid -2.252325 -0.662833)
					(end -2.051812 -1.0668)
				)
				(arc
					(start 2.051812 -1.0668)
					(mid 2.252296 -0.662822)
					(end 2.374138 -0.2286)
				)
				(xy 2.7432 -0.2286) (xy 2.7432 0.2286)
			)
			(stroke
				(width 0)
				(type default)
			)
			(fill no)
			(layer "F.CrtYd")
		)
		(fp_poly
			(pts
				(arc
					(start 2.786634 1.0795)
					(mid 0 3.124369)
					(end -2.786634 1.0795)
				)
				(xy -3.5814 1.0795) (xy -3.5814 -1.0795)
				(arc
					(start -2.624328 -1.0795)
					(mid -2.483414 -1.33481)
					(end -2.31775 -1.5748)
				)
				(xy -0.000762 -1.5748) (xy -0.000762 -1.067054)
				(arc
					(start -2.052066 -1.067054)
					(mid -2.252571 -0.663082)
					(end -2.374392 -0.228854)
				)
				(xy -2.743454 -0.228854) (xy -2.743454 0.228854)
				(arc
					(start -2.413254 0.228854)
					(mid 0 2.61659)
					(end 2.413254 0.228854)
				)
				(xy 2.743454 0.228854) (xy 2.743454 -0.228854)
				(arc
					(start 2.374392 -0.228854)
					(mid 2.252549 -0.663073)
					(end 2.052066 -1.067054)
				)
				(xy 0.000762 -1.067054) (xy 0.000762 -1.5748)
				(arc
					(start 2.31775 -1.5748)
					(mid 2.483417 -1.334811)
					(end 2.624328 -1.0795)
				)
				(xy 3.5814 -1.0795) (xy 3.5814 1.0795)
			)
			(stroke
				(width 0)
				(type default)
			)
			(fill no)
			(layer "F.CrtYd")
		)
		(fp_poly
			(pts
				(arc
					(start 2.786634 1.0795)
					(mid 0 3.124369)
					(end -2.786634 1.0795)
				)
				(xy -3.5814 1.0795) (xy -3.5814 -1.0795)
				(arc
					(start -2.624328 -1.0795)
					(mid -2.483414 -1.33481)
					(end -2.31775 -1.5748)
				)
				(arc
					(start 2.31775 -1.5748)
					(mid 2.483417 -1.334811)
					(end 2.624328 -1.0795)
				)
				(xy 3.5814 -1.0795) (xy 3.5814 1.0795)
			)
			(stroke
				(width 0)
				(type default)
			)
			(fill no)
			(layer "F.Fab")
		)
		(pad "B" thru_hole circle
			(at 0 0 180)
			(size 1.143 1.143)
			(drill 0.7874)
			(layers "*.Cu" "*.Mask")
			(remove_unused_layers no)
			(net "ISENSE_TMP421_1_BC")
			(clearance 0.1778)
			(thermal_gap 0.1778)
		)
		(pad "C" thru_hole circle
			(at -2.500122 0 180)
			(size 1.143 1.143)
			(drill 0.7874)
			(layers "*.Cu" "*.Mask")
			(remove_unused_layers no)
			(net "ISENSE_TMP421_1_BC")
			(clearance 0.1778)
			(thermal_gap 0.1778)
		)
		(pad "E" thru_hole circle
			(at 2.500122 0 180)
			(size 1.143 1.143)
			(drill 0.7874)
			(layers "*.Cu" "*.Mask")
			(remove_unused_layers no)
			(net "ISENSE_TMP421_1_E")
			(clearance 0.1778)
			(thermal_gap 0.1778)
		)
	)
)
